# TIMECARD (Time Appliance Project (Time Card)) — schematic netlist excerpt (pin names and nets, part order shuffled) for the footprints in the layout excerpt that follows; sources: Cadence DE-HDL packaged netlist, KiCad conversion of R4006-B0001-02_R01.brd

C151  CAPACITOR  0.1UF 10V 10%  pkg SMC_0402R_H022  page 14 : \1\ = XP2R5V_FPGA ; \2\ = SG
R317  RESISTOR  10KOHM 1%  pkg SMC_0402R_H016  page 26 : \1\ = XP3R3V_FPGA ; \2\ = R_RGB_LED_I2C_SDA

(kicad_pcb
	(version 20260206)
	(generator "pcbnew")
	(generator_version "10.0")
	(general
		(thickness 1.6)
		(legacy_teardrops no)
	)
	(paper "A4")
	(title_block
		(title "timecard-production-celestica-r4006 — R4006-B0001-02_R01.brd")
		(comment 1 "Time Appliance Project (Time Card) / footprints 823-824 of 1113")
	)
	(layers
		(0 "F.Cu" signal "TOP")
		(4 "In1.Cu" signal "L02_GND1")
		(6 "In2.Cu" signal "L03_SIG1")
		(8 "In3.Cu" signal "L04_GND2")
		(10 "In4.Cu" signal "L05_VCC1")
		(12 "In5.Cu" signal "L06_VCC2")
		(14 "In6.Cu" signal "L07_GND3")
		(16 "In7.Cu" signal "L08_SIG2")
		(18 "In8.Cu" signal "L09_GND4")
		(2 "B.Cu" signal "BOTTOM")
		(9 "F.Adhes" user "F.Adhesive")
		(11 "B.Adhes" user "B.Adhesive")
		(13 "F.Paste" user "Package Geometry/Pastemask Top")
		(15 "B.Paste" user "Package Geometry/Pastemask Bottom")
		(5 "F.SilkS" user "Ref Des/Silkscreen Top")
		(7 "B.SilkS" user "Ref Des/Silkscreen Bottom")
		(1 "F.Mask" user "Board Geometry/Soldermask Top")
		(3 "B.Mask" user "Board Geometry/Soldermask Bottom")
		(17 "Dwgs.User" user "User.Drawings")
		(19 "Cmts.User" user "User.Comments")
		(21 "Eco1.User" user "User.Eco1")
		(23 "Eco2.User" user "User.Eco2")
		(25 "Edge.Cuts" user "Board Geometry/Outline")
		(27 "Margin" user)
		(31 "F.CrtYd" user "Package Geometry/Place Bound Top")
		(29 "B.CrtYd" user "Package Geometry/Place Bound Bottom")
		(35 "F.Fab" user "Ref Des/Assembly Top")
		(33 "B.Fab" user "Ref Des/Assembly Bottom")
	)
	(footprint ""
		(layer "B.Cu")
		(at 107.823 -103.251 180)
		(property "Reference" "R317"
			(at -0.127 3.13563 0)
			(unlocked yes)
			(layer "B.SilkS")
			(effects
				(font
					(size 0.7874 0.5842)
					(thickness 0.1524)
				)
				(justify mirror)
			)
		)
		(property "Value" "VAL*"
			(at -0.02032 2.13233 180)
			(unlocked yes)
			(layer "B.Fab")
			(hide yes)
			(effects
				(font
					(size 0.7874 0.5842)
					(thickness 0.1524)
				)
				(justify mirror)
			)
		)
		(property "Tolerance" "TOL*"
			(at -0.044704 3.05435 180)
			(unlocked yes)
			(layer "Cmts.User")
			(hide yes)
			(effects
				(font
					(size 0.7874 0.5842)
					(thickness 0.1524)
				)
				(justify mirror)
			)
		)
		(property "User Part Number" "PARTNUM*"
			(at -0.02032 4.024884 180)
			(unlocked yes)
			(layer "Cmts.User")
			(hide yes)
			(effects
				(font
					(size 0.7874 0.5842)
					(thickness 0.1524)
				)
				(justify mirror)
			)
		)
		(property "Device Type" "RESISTOR-G155-11002-01,10KOHM,A"
			(at -0.008382 1.210564 180)
			(unlocked yes)
			(layer "B.Fab")
			(hide yes)
			(effects
				(font
					(size 0.7874 0.5842)
					(thickness 0.1524)
				)
				(justify mirror)
			)
		)
		(duplicate_pad_numbers_are_jumpers no)
		(fp_line
			(start 1.143 0.5588)
			(end -1.143 0.5588)
			(stroke
				(width 0.1)
				(type default)
			)
			(layer "B.SilkS")
		)
		(fp_line
			(start 1.143 -0.5588)
			(end 1.143 0.5588)
			(stroke
				(width 0.1)
				(type default)
			)
			(layer "B.SilkS")
		)
		(fp_line
			(start -1.143 0.5588)
			(end -1.143 -0.5588)
			(stroke
				(width 0.1)
				(type default)
			)
			(layer "B.SilkS")
		)
		(fp_line
			(start -1.143 -0.5588)
			(end 1.143 -0.5588)
			(stroke
				(width 0.1)
				(type default)
			)
			(layer "B.SilkS")
		)
		(fp_poly
			(pts
				(xy 1.143 0.5588) (xy -1.143 0.5588) (xy -1.143 -0.5588) (xy 1.143 -0.5588)
			)
			(stroke
				(width 0)
				(type default)
			)
			(fill no)
			(layer "B.CrtYd")
		)
		(fp_line
			(start 0.508 0.3048)
			(end -0.508 0.3048)
			(stroke
				(width 0.1)
				(type default)
			)
			(layer "B.Fab")
		)
		(fp_line
			(start 0.508 -0.3048)
			(end 0.508 0.3048)
			(stroke
				(width 0.1)
				(type default)
			)
			(layer "B.Fab")
		)
		(fp_line
			(start -0.508 0.3048)
			(end -0.508 -0.3048)
			(stroke
				(width 0.1)
				(type default)
			)
			(layer "B.Fab")
		)
		(fp_line
			(start -0.508 -0.3048)
			(end 0.508 -0.3048)
			(stroke
				(width 0.1)
				(type default)
			)
			(layer "B.Fab")
		)
		(pad "1" smd rect
			(at 0.5334 0)
			(size 0.7112 0.6096)
			(layers "B.Cu" "B.Mask" "B.Paste")
			(net "XP3R3V_FPGA")
		)
		(pad "2" smd rect
			(at -0.5334 0)
			(size 0.7112 0.6096)
			(layers "B.Cu" "B.Mask" "B.Paste")
			(net "R_RGB_LED_I2C_SDA")
		)
		(zone
			(layer "B.Cu")
			(hatch none 0.5)
			(connect_pads
				(clearance 0)
			)
			(min_thickness 0.25)
			(keepout
				(tracks allowed)
				(vias not_allowed)
				(pads allowed)
				(copperpour not_allowed)
				(footprints allowed)
			)
			(placement
				(enabled no)
				(sheetname "")
			)
			(fill
				(thermal_gap 0.5)
				(thermal_bridge_width 0.5)
				(island_removal_mode 0)
			)
			(polygon
				(pts
					(xy 107.7468 -103.5558) (xy 107.7468 -102.9462) (xy 107.8992 -102.9462) (xy 107.8992 -103.5558)
				)
			)
		)
		(zone
			(layer "B.Cu")
			(hatch none 0.5)
			(connect_pads
				(clearance 0)
			)
			(min_thickness 0.25)
			(keepout
				(tracks not_allowed)
				(vias allowed)
				(pads allowed)
				(copperpour not_allowed)
				(footprints allowed)
			)
			(placement
				(enabled no)
				(sheetname "")
			)
			(fill
				(thermal_gap 0.5)
				(thermal_bridge_width 0.5)
				(island_removal_mode 0)
			)
			(polygon
				(pts
					(xy 107.7468 -103.5558) (xy 107.7468 -102.9462) (xy 107.8992 -102.9462) (xy 107.8992 -103.5558)
				)
			)
		)
	)
	(footprint ""
		(layer "B.Cu")
		(at 118.346982 -39.823136)
		(property "Reference" "C151"
			(at 2.303018 -0.404114 0)
			(unlocked yes)
			(layer "B.SilkS")
			(effects
				(font
					(size 0.635 0.4064)
					(thickness 0.1524)
				)
				(justify mirror)
			)
		)
		(property "Value" "VAL*"
			(at 0 3.718306 0)
			(unlocked yes)
			(layer "B.Fab")
			(hide yes)
			(effects
				(font
					(size 0.7874 0.5842)
					(thickness 0.127)
				)
				(justify mirror)
			)
		)
		(property "Tolerance" "TOL*"
			(at 0 4.861306 0)
			(unlocked yes)
			(layer "Cmts.User")
			(hide yes)
			(effects
				(font
					(size 0.7874 0.5842)
					(thickness 0.127)
				)
				(justify mirror)
			)
		)
		(property "User Part Number" "PARTNUM*"
			(at 0 2.575306 0)
			(unlocked yes)
			(layer "Cmts.User")
			(hide yes)
			(effects
				(font
					(size 0.7874 0.5842)
					(thickness 0.127)
				)
				(justify mirror)
			)
		)
		(property "Device Type" "CAPACITOR-G105-0B104-CK,0.1UF,A"
			(at 0 1.432306 0)
			(unlocked yes)
			(layer "B.Fab")
			(hide yes)
			(effects
				(font
					(size 0.7874 0.5842)
					(thickness 0.127)
				)
				(justify mirror)
			)
		)
		(duplicate_pad_numbers_are_jumpers no)
		(fp_line
			(start -0.970026 -0.4699)
			(end -0.970026 0.4699)
			(stroke
				(width 0.1)
				(type default)
			)
			(layer "B.SilkS")
		)
		(fp_line
			(start -0.970026 0.4699)
			(end 0.970026 0.4699)
			(stroke
				(width 0.1)
				(type default)
			)
			(layer "B.SilkS")
		)
		(fp_line
			(start 0.970026 -0.4699)
			(end -0.970026 -0.4699)
			(stroke
				(width 0.1)
				(type default)
			)
			(layer "B.SilkS")
		)
		(fp_line
			(start 0.970026 0.4699)
			(end 0.970026 -0.4699)
			(stroke
				(width 0.1)
				(type default)
			)
			(layer "B.SilkS")
		)
		(fp_poly
			(pts
				(xy 0.970026 0.4699) (xy -0.970026 0.4699) (xy -0.970026 -0.4699) (xy 0.970026 -0.4699)
			)
			(stroke
				(width 0)
				(type default)
			)
			(fill no)
			(layer "B.CrtYd")
		)
		(fp_line
			(start -0.508 -0.3048)
			(end -0.508 0.3048)
			(stroke
				(width 0.1)
				(type default)
			)
			(layer "B.Fab")
		)
		(fp_line
			(start -0.508 0.3048)
			(end 0.508 0.3048)
			(stroke
				(width 0.1)
				(type default)
			)
			(layer "B.Fab")
		)
		(fp_line
			(start 0.508 -0.3048)
			(end -0.508 -0.3048)
			(stroke
				(width 0.1)
				(type default)
			)
			(layer "B.Fab")
		)
		(fp_line
			(start 0.508 0.3048)
			(end 0.508 -0.3048)
			(stroke
				(width 0.1)
				(type default)
			)
			(layer "B.Fab")
		)
		(pad "1" smd circle
			(at 0.500126 0 180)
			(size 0.635 0.635)
			(layers "B.Cu" "B.Mask" "B.Paste")
			(net "XP2R5V_FPGA")
		)
		(pad "2" smd circle
			(at -0.500126 0 180)
			(size 0.635 0.635)
			(layers "B.Cu" "B.Mask" "B.Paste")
			(net "SG")
		)
	)
)
